(kicad_pcb
	(version 20260206)
	(generator "pcbnew")
	(generator_version "10.0")
	(general
		(thickness 1.6)
		(legacy_teardrops no)
	)
	(paper "A4")
	(title_block
		(title "04192023_DAF0TMB3IC0_F0TG_MB_C_brd_V02_OCP.brd")
		(comment 1 "Grand Teton / footprints 786-792 of 8354")
	)
	(layers
		(0 "F.Cu" signal "TOP")
		(4 "In1.Cu" signal "GND")
		(6 "In2.Cu" signal "IN1")
		(8 "In3.Cu" signal "GND1")
		(10 "In4.Cu" signal "IN2")
		(12 "In5.Cu" signal "GND2")
		(14 "In6.Cu" signal "IN3")
		(16 "In7.Cu" signal "GND3")
		(18 "In8.Cu" signal "VCC")
		(20 "In9.Cu" signal "VCC1")
		(22 "In10.Cu" signal "GND4")
		(24 "In11.Cu" signal "IN4")
		(26 "In12.Cu" signal "GND5")
		(28 "In13.Cu" signal "IN5")
		(30 "In14.Cu" signal "GND6")
		(32 "In15.Cu" signal "IN6")
		(34 "In16.Cu" signal "GND7")
		(2 "B.Cu" signal "BOTTOM")
		(9 "F.Adhes" user "F.Adhesive")
		(11 "B.Adhes" user "B.Adhesive")
		(13 "F.Paste" user "Package Geometry/Pastemask Top")
		(15 "B.Paste" user "Package Geometry/Pastemask Bottom")
		(5 "F.SilkS" user "Ref Des/Silkscreen Top")
		(7 "B.SilkS" user "Ref Des/Silkscreen Bottom")
		(1 "F.Mask" user "Board Geometry/Soldermask Top")
		(3 "B.Mask" user "Board Geometry/Soldermask Bottom")
		(17 "Dwgs.User" user "User.Drawings")
		(19 "Cmts.User" user "User.Comments")
		(21 "Eco1.User" user "User.Eco1")
		(23 "Eco2.User" user "User.Eco2")
		(25 "Edge.Cuts" user "Board Geometry/Outline")
		(27 "Margin" user)
		(31 "F.CrtYd" user "Package Geometry/Place Bound Top")
		(29 "B.CrtYd" user "Package Geometry/Place Bound Bottom")
		(35 "F.Fab" user "Ref Des/Assembly Top")
		(33 "B.Fab" user "Ref Des/Assembly Bottom")
	)
	(footprint ""
		(layer "F.Cu")
		(at 106.71175 -166.626032)
		(property "Reference" "H43"
			(at -5.286502 -3.414776 0)
			(unlocked yes)
			(layer "F.SilkS")
			(effects
				(font
					(size 0.7874 0.5842)
					(thickness 0.1524)
				)
				(justify left)
			)
		)
		(property "Value" ""
			(at 0 0 0)
			(layer "F.Fab")
			(effects
				(font
					(size 1.27 1.27)
				)
			)
		)
		(duplicate_pad_numbers_are_jumpers no)
		(pad "1" thru_hole circle
			(at 0 0)
			(size 6.1976 6.1976)
			(drill 3.7338)
			(layers "*.Cu" "*.Mask")
			(remove_unused_layers no)
			(net "GND")
			(clearance -0.9779)
			(padstack
				(mode front_inner_back)
				(layer "Inner"
					(shape circle)
					(size 5.5372 5.5372)
					(clearance -0.6477)
				)
				(layer "B.Cu"
					(shape circle)
					(size 6.1976 6.1976)
					(clearance -0.9779)
				)
			)
		)
	)
	(footprint ""
		(layer "F.Cu")
		(at 145.63344 -31.58744 90)
		(property "Reference" "C6003"
			(at 0 0 90)
			(layer "F.SilkS")
			(hide yes)
			(effects
				(font
					(size 1.27 1.27)
				)
			)
		)
		(property "Value" ""
			(at 0 0 90)
			(layer "F.Fab")
			(effects
				(font
					(size 1.27 1.27)
				)
			)
		)
		(duplicate_pad_numbers_are_jumpers no)
		(fp_line
			(start 0.7874 -0.4064)
			(end 0.7874 0.4064)
			(stroke
				(width 0.1524)
				(type default)
			)
			(layer "F.SilkS")
		)
		(fp_line
			(start -0.7874 -0.4064)
			(end 0.7874 -0.4064)
			(stroke
				(width 0.1524)
				(type default)
			)
			(layer "F.SilkS")
		)
		(fp_line
			(start 0.7874 0.4064)
			(end -0.7874 0.4064)
			(stroke
				(width 0.1524)
				(type default)
			)
			(layer "F.SilkS")
		)
		(fp_line
			(start -0.7874 0.4064)
			(end -0.7874 -0.4064)
			(stroke
				(width 0.1524)
				(type default)
			)
			(layer "F.SilkS")
		)
		(fp_line
			(start 0.6858 -0.3048)
			(end 0.6858 0.3048)
			(stroke
				(width 0.1)
				(type default)
			)
			(layer "F.Fab")
		)
		(fp_line
			(start 0.1016 -0.3048)
			(end 0.6858 -0.3048)
			(stroke
				(width 0.1)
				(type default)
			)
			(layer "F.Fab")
		)
		(fp_line
			(start -0.1016 -0.3048)
			(end -0.1016 -0.2794)
			(stroke
				(width 0.1)
				(type default)
			)
			(layer "F.Fab")
		)
		(fp_line
			(start -0.6858 -0.3048)
			(end -0.1016 -0.3048)
			(stroke
				(width 0.1)
				(type default)
			)
			(layer "F.Fab")
		)
		(fp_line
			(start 0.1016 -0.2794)
			(end 0.1016 -0.3048)
			(stroke
				(width 0.1)
				(type default)
			)
			(layer "F.Fab")
		)
		(fp_line
			(start -0.1016 -0.2794)
			(end 0.1016 -0.2794)
			(stroke
				(width 0.1)
				(type default)
			)
			(layer "F.Fab")
		)
		(fp_line
			(start 0.1016 0.2794)
			(end -0.1016 0.2794)
			(stroke
				(width 0.1)
				(type default)
			)
			(layer "F.Fab")
		)
		(fp_line
			(start -0.1016 0.2794)
			(end -0.1016 0.3048)
			(stroke
				(width 0.1)
				(type default)
			)
			(layer "F.Fab")
		)
		(fp_line
			(start 0.6858 0.3048)
			(end 0.1016 0.3048)
			(stroke
				(width 0.1)
				(type default)
			)
			(layer "F.Fab")
		)
		(fp_line
			(start 0.1016 0.3048)
			(end 0.1016 0.2794)
			(stroke
				(width 0.1)
				(type default)
			)
			(layer "F.Fab")
		)
		(fp_line
			(start -0.1016 0.3048)
			(end -0.6858 0.3048)
			(stroke
				(width 0.1)
				(type default)
			)
			(layer "F.Fab")
		)
		(fp_line
			(start -0.6858 0.3048)
			(end -0.6858 -0.3048)
			(stroke
				(width 0.1)
				(type default)
			)
			(layer "F.Fab")
		)
		(pad "1" smd rect
			(at -0.40005 0 270)
			(size 0.4572 0.508)
			(layers "F.Cu" "F.Mask" "F.Paste")
			(net "USB3_CPU0_BMC_TX_DP")
		)
		(pad "2" smd rect
			(at 0.40005 0 270)
			(size 0.4572 0.508)
			(layers "F.Cu" "F.Mask" "F.Paste")
			(net "USB3_CPU0_BMC_TX_C1_DP")
		)
	)
	(footprint ""
		(layer "F.Cu")
		(at 204.7621 -404.020782)
		(property "Reference" "PC2182"
			(at 0 0 0)
			(layer "F.SilkS")
			(hide yes)
			(effects
				(font
					(size 1.27 1.27)
				)
			)
		)
		(property "Value" ""
			(at 0 0 0)
			(layer "F.Fab")
			(effects
				(font
					(size 1.27 1.27)
				)
			)
		)
		(duplicate_pad_numbers_are_jumpers no)
		(fp_line
			(start -0.7874 -0.4064)
			(end 0.7874 -0.4064)
			(stroke
				(width 0.1524)
				(type default)
			)
			(layer "F.SilkS")
		)
		(fp_line
			(start -0.7874 0.4064)
			(end -0.7874 -0.4064)
			(stroke
				(width 0.1524)
				(type default)
			)
			(layer "F.SilkS")
		)
		(fp_line
			(start 0.7874 -0.4064)
			(end 0.7874 0.4064)
			(stroke
				(width 0.1524)
				(type default)
			)
			(layer "F.SilkS")
		)
		(fp_line
			(start 0.7874 0.4064)
			(end -0.7874 0.4064)
			(stroke
				(width 0.1524)
				(type default)
			)
			(layer "F.SilkS")
		)
		(fp_line
			(start -0.67945 -0.305054)
			(end -0.12065 -0.305054)
			(stroke
				(width 0.1)
				(type default)
			)
			(layer "F.Fab")
		)
		(fp_line
			(start -0.67945 0.3048)
			(end -0.67945 -0.305054)
			(stroke
				(width 0.1)
				(type default)
			)
			(layer "F.Fab")
		)
		(fp_line
			(start -0.12065 -0.305054)
			(end -0.12065 -0.2794)
			(stroke
				(width 0.1)
				(type default)
			)
			(layer "F.Fab")
		)
		(fp_line
			(start -0.12065 -0.2794)
			(end 0.12065 -0.2794)
			(stroke
				(width 0.1)
				(type default)
			)
			(layer "F.Fab")
		)
		(fp_line
			(start -0.12065 0.2794)
			(end -0.12065 0.3048)
			(stroke
				(width 0.1)
				(type default)
			)
			(layer "F.Fab")
		)
		(fp_line
			(start -0.12065 0.3048)
			(end -0.67945 0.3048)
			(stroke
				(width 0.1)
				(type default)
			)
			(layer "F.Fab")
		)
		(fp_line
			(start 0.120396 0.2794)
			(end -0.12065 0.2794)
			(stroke
				(width 0.1)
				(type default)
			)
			(layer "F.Fab")
		)
		(fp_line
			(start 0.120396 0.3048)
			(end 0.120396 0.2794)
			(stroke
				(width 0.1)
				(type default)
			)
			(layer "F.Fab")
		)
		(fp_line
			(start 0.12065 -0.3048)
			(end 0.67945 -0.3048)
			(stroke
				(width 0.1)
				(type default)
			)
			(layer "F.Fab")
		)
		(fp_line
			(start 0.12065 -0.2794)
			(end 0.12065 -0.3048)
			(stroke
				(width 0.1)
				(type default)
			)
			(layer "F.Fab")
		)
		(fp_line
			(start 0.67945 -0.3048)
			(end 0.67945 0.3048)
			(stroke
				(width 0.1)
				(type default)
			)
			(layer "F.Fab")
		)
		(fp_line
			(start 0.67945 0.3048)
			(end 0.120396 0.3048)
			(stroke
				(width 0.1)
				(type default)
			)
			(layer "F.Fab")
		)
		(pad "1" smd circle
			(at -0.40005 0)
			(size 0 0)
			(layers "F.Cu" "F.Mask" "F.Paste")
			(net "HSC_ON")
		)
		(pad "2" smd circle
			(at 0.40005 0)
			(size 0 0)
			(layers "F.Cu" "F.Mask" "F.Paste")
			(net "AGND_HSC")
		)
	)
	(footprint ""
		(layer "F.Cu")
		(at 296.215562 -19.247358 -90)
		(property "Reference" "C1564"
			(at 0 0 270)
			(layer "F.SilkS")
			(hide yes)
			(effects
				(font
					(size 1.27 1.27)
				)
			)
		)
		(property "Value" ""
			(at 0 0 270)
			(layer "F.Fab")
			(effects
				(font
					(size 1.27 1.27)
				)
			)
		)
		(duplicate_pad_numbers_are_jumpers no)
		(fp_line
			(start -0.7874 0.4064)
			(end -0.7874 -0.4064)
			(stroke
				(width 0.1524)
				(type default)
			)
			(layer "F.SilkS")
		)
		(fp_line
			(start 0.7874 0.4064)
			(end -0.7874 0.4064)
			(stroke
				(width 0.1524)
				(type default)
			)
			(layer "F.SilkS")
		)
		(fp_line
			(start -0.7874 -0.4064)
			(end 0.7874 -0.4064)
			(stroke
				(width 0.1524)
				(type default)
			)
			(layer "F.SilkS")
		)
		(fp_line
			(start 0.7874 -0.4064)
			(end 0.7874 0.4064)
			(stroke
				(width 0.1524)
				(type default)
			)
			(layer "F.SilkS")
		)
		(fp_line
			(start -0.67945 0.3048)
			(end -0.67945 -0.305054)
			(stroke
				(width 0.1)
				(type default)
			)
			(layer "F.Fab")
		)
		(fp_line
			(start -0.12065 0.3048)
			(end -0.67945 0.3048)
			(stroke
				(width 0.1)
				(type default)
			)
			(layer "F.Fab")
		)
		(fp_line
			(start 0.120396 0.3048)
			(end 0.120396 0.2794)
			(stroke
				(width 0.1)
				(type default)
			)
			(layer "F.Fab")
		)
		(fp_line
			(start 0.67945 0.3048)
			(end 0.120396 0.3048)
			(stroke
				(width 0.1)
				(type default)
			)
			(layer "F.Fab")
		)
		(fp_line
			(start -0.12065 0.2794)
			(end -0.12065 0.3048)
			(stroke
				(width 0.1)
				(type default)
			)
			(layer "F.Fab")
		)
		(fp_line
			(start 0.120396 0.2794)
			(end -0.12065 0.2794)
			(stroke
				(width 0.1)
				(type default)
			)
			(layer "F.Fab")
		)
		(fp_line
			(start -0.12065 -0.2794)
			(end 0.12065 -0.2794)
			(stroke
				(width 0.1)
				(type default)
			)
			(layer "F.Fab")
		)
		(fp_line
			(start 0.12065 -0.2794)
			(end 0.12065 -0.3048)
			(stroke
				(width 0.1)
				(type default)
			)
			(layer "F.Fab")
		)
		(fp_line
			(start 0.12065 -0.3048)
			(end 0.67945 -0.3048)
			(stroke
				(width 0.1)
				(type default)
			)
			(layer "F.Fab")
		)
		(fp_line
			(start 0.67945 -0.3048)
			(end 0.67945 0.3048)
			(stroke
				(width 0.1)
				(type default)
			)
			(layer "F.Fab")
		)
		(fp_line
			(start -0.67945 -0.305054)
			(end -0.12065 -0.305054)
			(stroke
				(width 0.1)
				(type default)
			)
			(layer "F.Fab")
		)
		(fp_line
			(start -0.12065 -0.305054)
			(end -0.12065 -0.2794)
			(stroke
				(width 0.1)
				(type default)
			)
			(layer "F.Fab")
		)
		(pad "1" smd circle
			(at -0.40005 0 270)
			(size 0 0)
			(layers "F.Cu" "F.Mask" "F.Paste")
			(net "P1V5_BAT_OUT")
		)
		(pad "2" smd circle
			(at 0.40005 0 270)
			(size 0 0)
			(layers "F.Cu" "F.Mask" "F.Paste")
			(net "GND")
		)
	)
	(footprint ""
		(layer "F.Cu")
		(at 116.331238 -41.17975 90)
		(property "Reference" "R6284"
			(at 0 0 90)
			(layer "F.SilkS")
			(hide yes)
			(effects
				(font
					(size 1.27 1.27)
				)
			)
		)
		(property "Value" ""
			(at 0 0 90)
			(layer "F.Fab")
			(effects
				(font
					(size 1.27 1.27)
				)
			)
		)
		(duplicate_pad_numbers_are_jumpers no)
		(fp_line
			(start 0.7874 -0.4064)
			(end 0.7874 0.4064)
			(stroke
				(width 0.1524)
				(type default)
			)
			(layer "F.SilkS")
		)
		(fp_line
			(start -0.7874 -0.4064)
			(end 0.7874 -0.4064)
			(stroke
				(width 0.1524)
				(type default)
			)
			(layer "F.SilkS")
		)
		(fp_line
			(start 0.7874 0.4064)
			(end -0.7874 0.4064)
			(stroke
				(width 0.1524)
				(type default)
			)
			(layer "F.SilkS")
		)
		(fp_line
			(start -0.7874 0.4064)
			(end -0.7874 -0.4064)
			(stroke
				(width 0.1524)
				(type default)
			)
			(layer "F.SilkS")
		)
		(fp_line
			(start -0.12065 -0.305054)
			(end -0.12065 -0.2794)
			(stroke
				(width 0.1)
				(type default)
			)
			(layer "F.Fab")
		)
		(fp_line
			(start -0.67945 -0.305054)
			(end -0.12065 -0.305054)
			(stroke
				(width 0.1)
				(type default)
			)
			(layer "F.Fab")
		)
		(fp_line
			(start 0.67945 -0.3048)
			(end 0.67945 0.3048)
			(stroke
				(width 0.1)
				(type default)
			)
			(layer "F.Fab")
		)
		(fp_line
			(start 0.12065 -0.3048)
			(end 0.67945 -0.3048)
			(stroke
				(width 0.1)
				(type default)
			)
			(layer "F.Fab")
		)
		(fp_line
			(start 0.12065 -0.2794)
			(end 0.12065 -0.3048)
			(stroke
				(width 0.1)
				(type default)
			)
			(layer "F.Fab")
		)
		(fp_line
			(start -0.12065 -0.2794)
			(end 0.12065 -0.2794)
			(stroke
				(width 0.1)
				(type default)
			)
			(layer "F.Fab")
		)
		(fp_line
			(start 0.120396 0.2794)
			(end -0.12065 0.2794)
			(stroke
				(width 0.1)
				(type default)
			)
			(layer "F.Fab")
		)
		(fp_line
			(start -0.12065 0.2794)
			(end -0.12065 0.3048)
			(stroke
				(width 0.1)
				(type default)
			)
			(layer "F.Fab")
		)
		(fp_line
			(start 0.67945 0.3048)
			(end 0.120396 0.3048)
			(stroke
				(width 0.1)
				(type default)
			)
			(layer "F.Fab")
		)
		(fp_line
			(start 0.120396 0.3048)
			(end 0.120396 0.2794)
			(stroke
				(width 0.1)
				(type default)
			)
			(layer "F.Fab")
		)
		(fp_line
			(start -0.12065 0.3048)
			(end -0.67945 0.3048)
			(stroke
				(width 0.1)
				(type default)
			)
			(layer "F.Fab")
		)
		(fp_line
			(start -0.67945 0.3048)
			(end -0.67945 -0.305054)
			(stroke
				(width 0.1)
				(type default)
			)
			(layer "F.Fab")
		)
		(pad "1" smd circle
			(at -0.40005 0 90)
			(size 0 0)
			(layers "F.Cu" "F.Mask" "F.Paste")
			(net "USB_HUB2_TI_FULLPWRMGMTZ_MRP_PROG_FUNC3")
		)
		(pad "2" smd circle
			(at 0.40005 0 90)
			(size 0 0)
			(layers "F.Cu" "F.Mask" "F.Paste")
			(net "GND")
		)
	)
	(footprint ""
		(layer "F.Cu")
		(at 254.592836 -123.10745)
		(property "Reference" "R3724"
			(at 0 0 0)
			(layer "F.SilkS")
			(hide yes)
			(effects
				(font
					(size 1.27 1.27)
				)
			)
		)
		(property "Value" ""
			(at 0 0 0)
			(layer "F.Fab")
			(effects
				(font
					(size 1.27 1.27)
				)
			)
		)
		(duplicate_pad_numbers_are_jumpers no)
		(fp_line
			(start -0.7874 -0.4064)
			(end 0.7874 -0.4064)
			(stroke
				(width 0.1524)
				(type default)
			)
			(layer "F.SilkS")
		)
		(fp_line
			(start -0.7874 0.4064)
			(end -0.7874 -0.4064)
			(stroke
				(width 0.1524)
				(type default)
			)
			(layer "F.SilkS")
		)
		(fp_line
			(start 0.7874 -0.4064)
			(end 0.7874 0.4064)
			(stroke
				(width 0.1524)
				(type default)
			)
			(layer "F.SilkS")
		)
		(fp_line
			(start 0.7874 0.4064)
			(end -0.7874 0.4064)
			(stroke
				(width 0.1524)
				(type default)
			)
			(layer "F.SilkS")
		)
		(fp_line
			(start -0.67945 -0.305054)
			(end -0.12065 -0.305054)
			(stroke
				(width 0.1)
				(type default)
			)
			(layer "F.Fab")
		)
		(fp_line
			(start -0.67945 0.3048)
			(end -0.67945 -0.305054)
			(stroke
				(width 0.1)
				(type default)
			)
			(layer "F.Fab")
		)
		(fp_line
			(start -0.12065 -0.305054)
			(end -0.12065 -0.2794)
			(stroke
				(width 0.1)
				(type default)
			)
			(layer "F.Fab")
		)
		(fp_line
			(start -0.12065 -0.2794)
			(end 0.12065 -0.2794)
			(stroke
				(width 0.1)
				(type default)
			)
			(layer "F.Fab")
		)
		(fp_line
			(start -0.12065 0.2794)
			(end -0.12065 0.3048)
			(stroke
				(width 0.1)
				(type default)
			)
			(layer "F.Fab")
		)
		(fp_line
			(start -0.12065 0.3048)
			(end -0.67945 0.3048)
			(stroke
				(width 0.1)
				(type default)
			)
			(layer "F.Fab")
		)
		(fp_line
			(start 0.120396 0.2794)
			(end -0.12065 0.2794)
			(stroke
				(width 0.1)
				(type default)
			)
			(layer "F.Fab")
		)
		(fp_line
			(start 0.120396 0.3048)
			(end 0.120396 0.2794)
			(stroke
				(width 0.1)
				(type default)
			)
			(layer "F.Fab")
		)
		(fp_line
			(start 0.12065 -0.3048)
			(end 0.67945 -0.3048)
			(stroke
				(width 0.1)
				(type default)
			)
			(layer "F.Fab")
		)
		(fp_line
			(start 0.12065 -0.2794)
			(end 0.12065 -0.3048)
			(stroke
				(width 0.1)
				(type default)
			)
			(layer "F.Fab")
		)
		(fp_line
			(start 0.67945 -0.3048)
			(end 0.67945 0.3048)
			(stroke
				(width 0.1)
				(type default)
			)
			(layer "F.Fab")
		)
		(fp_line
			(start 0.67945 0.3048)
			(end 0.120396 0.3048)
			(stroke
				(width 0.1)
				(type default)
			)
			(layer "F.Fab")
		)
		(pad "1" smd circle
			(at -0.40005 0)
			(size 0 0)
			(layers "F.Cu" "F.Mask" "F.Paste")
			(net "P3V3_AUX")
		)
		(pad "2" smd circle
			(at 0.40005 0)
			(size 0 0)
			(layers "F.Cu" "F.Mask" "F.Paste")
			(net "SMB_VR_3V3AUX_SDA")
		)
	)
	(footprint ""
		(layer "F.Cu")
		(at 118.11 -401.1676)
		(property "Reference" "R1448"
			(at 0 0 0)
			(layer "F.SilkS")
			(hide yes)
			(effects
				(font
					(size 1.27 1.27)
				)
			)
		)
		(property "Value" ""
			(at 0 0 0)
			(layer "F.Fab")
			(effects
				(font
					(size 1.27 1.27)
				)
			)
		)
		(duplicate_pad_numbers_are_jumpers no)
		(fp_line
			(start -0.32512 -0.175006)
			(end 0.32512 -0.175006)
			(stroke
				(width 0.1)
				(type default)
			)
			(layer "F.Fab")
		)
		(fp_line
			(start -0.32512 0.175006)
			(end -0.32512 -0.175006)
			(stroke
				(width 0.1)
				(type default)
			)
			(layer "F.Fab")
		)
		(fp_line
			(start 0.32512 -0.175006)
			(end 0.32512 0.175006)
			(stroke
				(width 0.1)
				(type default)
			)
			(layer "F.Fab")
		)
		(fp_line
			(start 0.32512 0.175006)
			(end -0.32512 0.175006)
			(stroke
				(width 0.1)
				(type default)
			)
			(layer "F.Fab")
		)
		(pad "1" smd rect
			(at -0.2667 0)
			(size 0.3048 0.381)
			(layers "F.Cu" "F.Mask" "F.Paste")
			(net "P1V8_CPU1_RT_1D")
		)
		(pad "2" smd rect
			(at 0.2667 0 180)
			(size 0.3048 0.381)
			(layers "F.Cu" "F.Mask" "F.Paste")
			(net "SMB_RT_CPU1_P1_ROM_MUX_1D_SDA")
		)
	)
)
